#ISCELL
  mstr_symbols design_note *
  *
#ISCELL
  mstr_symbols intel_corp_bpage *
  *
#ISCELL
  mstr_symbols vcc_core *
  page36_i12
#ISCELL
  mstr_symbols vcc_core *
  page36_i13
#ISCELL
  mstr_symbols vcc_core *
  page36_i14
#CELL
  chpset_lib skx_ext_b *
  page36_i15
#CELL
  chpset_lib skx_ext_b *
  page36_i16
#ISCELL
  mstr_symbols vcc_core *
  page36_i17
#ISCELL
  mstr_standard offpage *
  page36_i5
#ISCELL
  mstr_standard offpage *
  page36_i8
